(kicad_pcb
	(version 20241229)
	(generator "pcbnew")
	(generator_version "9.0")
	(general
		(thickness 1.6)
		(legacy_teardrops no)
	)
	(paper "A4")
	(title_block
		(title "OCuLink to PCIe adapter")
		(date "2025-06-18")
		(rev "1.0.0")
		(company "Antmicro Ltd")
		(comment 1 "www.antmicro.com")
		(comment 9 "footprints 133-136 of 159")
	)
	(layers
		(0 "F.Cu" signal)
		(4 "In1.Cu" signal)
		(6 "In2.Cu" signal)
		(2 "B.Cu" signal)
		(9 "F.Adhes" user "F.Adhesive")
		(11 "B.Adhes" user "B.Adhesive")
		(13 "F.Paste" user)
		(15 "B.Paste" user)
		(5 "F.SilkS" user "F.Silkscreen")
		(7 "B.SilkS" user "B.Silkscreen")
		(1 "F.Mask" user)
		(3 "B.Mask" user)
		(17 "Dwgs.User" user "User.Drawings")
		(19 "Cmts.User" user "User.Comments")
		(21 "Eco1.User" user "User.Eco1")
		(23 "Eco2.User" user "User.Eco2")
		(25 "Edge.Cuts" user)
		(27 "Margin" user)
		(31 "F.CrtYd" user "F.Courtyard")
		(29 "B.CrtYd" user "B.Courtyard")
		(35 "F.Fab" user)
		(33 "B.Fab" user)
	)
	(footprint "antmicro-footprints:USON-10_2.5x1mm_P0.5mm"
		(layer "F.Cu")
		(at 138.579 47.014 -90)
		(descr "USON-10 2.5x1mm_ Pitch 0.5mm")
		(tags "USON-10 2.5x1mm Pitch 0.5mm")
		(property "Reference" "D12"
			(at 1.048001 -0.262467 180)
			(layer "F.SilkS")
			(effects
				(font
					(size 0.7 0.7)
					(thickness 0.15)
				)
				(justify right top)
			)
		)
		(property "Value" "ESD204DQAR"
			(at 0.018 2.499 90)
			(layer "F.Fab")
			(effects
				(font
					(size 0.7 0.7)
					(thickness 0.15)
				)
				(justify right top)
			)
		)
		(property "Datasheet" "https://www.ti.com/lit/ds/symlink/esd204.pdf?ts=1706004844383&ref_url=https%253A%252F%252Fwww.ti.com%252Finterface%252Fdiodes%252Fesd-protection-diodes%252Fproducts.html"
			(at 0 0 90)
			(layer "F.Fab")
			(hide yes)
			(effects
				(font
					(size 1.27 1.27)
					(thickness 0.15)
				)
			)
		)
		(property "Description" "TVS diode array, 30 kV, USON-10, 3.6 V, 0.55 pF"
			(at 0 0 90)
			(layer "F.Fab")
			(hide yes)
			(effects
				(font
					(size 1.27 1.27)
					(thickness 0.15)
				)
			)
		)
		(property "MPN" "ESD204DQAR"
			(at 0 0 270)
			(unlocked yes)
			(layer "F.Fab")
			(hide yes)
			(effects
				(font
					(size 1 1)
					(thickness 0.15)
				)
			)
		)
		(property "Manufacturer" "Texas Instruments"
			(at 0 0 270)
			(unlocked yes)
			(layer "F.Fab")
			(hide yes)
			(effects
				(font
					(size 1 1)
					(thickness 0.15)
				)
			)
		)
		(property "Author" "Antmicro"
			(at 0 0 270)
			(unlocked yes)
			(layer "F.Fab")
			(hide yes)
			(effects
				(font
					(size 1 1)
					(thickness 0.15)
				)
			)
		)
		(property "License" "Apache-2.0"
			(at 0 0 270)
			(unlocked yes)
			(layer "F.Fab")
			(hide yes)
			(effects
				(font
					(size 1 1)
					(thickness 0.15)
				)
			)
		)
		(sheetname "/OCuLink/")
		(sheetfile "oculink.kicad_sch")
		(attr smd)
		(fp_line
			(start 0.498 1.398)
			(end -0.5 1.398)
			(stroke
				(width 0.15)
				(type solid)
			)
			(layer "F.SilkS")
		)
		(fp_line
			(start 0.498 -1.401)
			(end -0.5 -1.401)
			(stroke
				(width 0.15)
				(type solid)
			)
			(layer "F.SilkS")
		)
		(fp_circle
			(center -0.68 -1.27)
			(end -0.63 -1.27)
			(stroke
				(width 0.15)
				(type solid)
			)
			(fill yes)
			(layer "F.SilkS")
		)
		(fp_rect
			(start -0.8 -1.5)
			(end 0.8 1.499)
			(stroke
				(width 0.05)
				(type solid)
			)
			(fill no)
			(layer "F.CrtYd")
		)
		(fp_line
			(start -0.5 1.249)
			(end 0.498 1.249)
			(stroke
				(width 0.15)
				(type solid)
			)
			(layer "F.Fab")
		)
		(fp_line
			(start -0.5 -1)
			(end -0.5 1.249)
			(stroke
				(width 0.15)
				(type solid)
			)
			(layer "F.Fab")
		)
		(fp_line
			(start -0.25 -1.25)
			(end -0.5 -1)
			(stroke
				(width 0.15)
				(type solid)
			)
			(layer "F.Fab")
		)
		(fp_line
			(start 0.498 -1.25)
			(end 0.498 1.249)
			(stroke
				(width 0.15)
				(type solid)
			)
			(layer "F.Fab")
		)
		(fp_line
			(start 0.498 -1.25)
			(end -0.25 -1.25)
			(stroke
				(width 0.15)
				(type solid)
			)
			(layer "F.Fab")
		)
		(fp_text user "License: Apache-2.0"
			(at -0.802 6.9 90)
			(layer "F.Fab")
			(effects
				(font
					(size 0.7 0.7)
					(thickness 0.15)
				)
				(justify right top)
			)
		)
		(fp_text user "Author: Antmicro"
			(at -0.802 5.7 90)
			(layer "F.Fab")
			(effects
				(font
					(size 0.7 0.7)
					(thickness 0.15)
				)
				(justify right top)
			)
		)
		(fp_text user "${REFERENCE}"
			(at 0 -0.000501 90)
			(layer "F.Fab")
			(effects
				(font
					(size 0.7 0.7)
					(thickness 0.15)
				)
				(justify right top)
			)
		)
		(pad "1" smd roundrect
			(at -0.387 -1 180)
			(size 0.25 0.55)
			(layers "F.Cu" "F.Mask" "F.Paste")
			(roundrect_rratio 0.25)
			(net 72 "/OCuLink/PCIe_{x4}.TX0+")
			(pintype "passive")
		)
		(pad "2" smd roundrect
			(at -0.387 -0.5 180)
			(size 0.25 0.55)
			(layers "F.Cu" "F.Mask" "F.Paste")
			(roundrect_rratio 0.25)
			(net 74 "/OCuLink/PCIe_{x4}.TX0-")
			(pintype "passive")
		)
		(pad "3" smd roundrect
			(at -0.387 0 180)
			(size 0.4 0.55)
			(layers "F.Cu" "F.Mask" "F.Paste")
			(roundrect_rratio 0.25)
			(net 66 "GND")
			(pintype "power_in")
		)
		(pad "4" smd roundrect
			(at -0.387 0.498 180)
			(size 0.25 0.55)
			(layers "F.Cu" "F.Mask" "F.Paste")
			(roundrect_rratio 0.25)
			(net 77 "/OCuLink/PCIe_{x4}.TX1+")
			(pintype "passive")
		)
		(pad "5" smd roundrect
			(at -0.387 0.998 180)
			(size 0.25 0.55)
			(layers "F.Cu" "F.Mask" "F.Paste")
			(roundrect_rratio 0.25)
			(net 69 "/OCuLink/PCIe_{x4}.TX1-")
			(pintype "passive")
		)
		(pad "6" smd roundrect
			(at 0.385 0.998 180)
			(size 0.25 0.55)
			(layers "F.Cu" "F.Mask" "F.Paste")
			(roundrect_rratio 0.25)
			(net 69 "/OCuLink/PCIe_{x4}.TX1-")
			(pintype "passive")
		)
		(pad "7" smd roundrect
			(at 0.385 0.498 180)
			(size 0.25 0.55)
			(layers "F.Cu" "F.Mask" "F.Paste")
			(roundrect_rratio 0.25)
			(net 77 "/OCuLink/PCIe_{x4}.TX1+")
			(pintype "passive")
		)
		(pad "8" smd roundrect
			(at 0.385 0 180)
			(size 0.4 0.55)
			(layers "F.Cu" "F.Mask" "F.Paste")
			(roundrect_rratio 0.25)
			(net 66 "GND")
			(pintype "passive")
		)
		(pad "9" smd roundrect
			(at 0.385 -0.5 180)
			(size 0.25 0.55)
			(layers "F.Cu" "F.Mask" "F.Paste")
			(roundrect_rratio 0.25)
			(net 74 "/OCuLink/PCIe_{x4}.TX0-")
			(pintype "passive")
		)
		(pad "10" smd roundrect
			(at 0.385 -1 180)
			(size 0.25 0.55)
			(layers "F.Cu" "F.Mask" "F.Paste")
			(roundrect_rratio 0.25)
			(net 72 "/OCuLink/PCIe_{x4}.TX0+")
			(pintype "passive")
		)
	)
	(footprint "antmicro-footprints:USON-10_2.5x1mm_P0.5mm"
		(layer "F.Cu")
		(at 124.298 43.387 -90)
		(descr "USON-10 2.5x1mm_ Pitch 0.5mm")
		(tags "USON-10 2.5x1mm Pitch 0.5mm")
		(property "Reference" "D11"
			(at 1.113 -0.452 180)
			(layer "F.SilkS")
			(effects
				(font
					(size 0.7 0.7)
					(thickness 0.15)
				)
				(justify right top)
			)
		)
		(property "Value" "ESD204DQAR"
			(at 0.018 2.499 90)
			(layer "F.Fab")
			(effects
				(font
					(size 0.7 0.7)
					(thickness 0.15)
				)
				(justify right top)
			)
		)
		(property "Datasheet" "https://www.ti.com/lit/ds/symlink/esd204.pdf?ts=1706004844383&ref_url=https%253A%252F%252Fwww.ti.com%252Finterface%252Fdiodes%252Fesd-protection-diodes%252Fproducts.html"
			(at 0 0 90)
			(layer "F.Fab")
			(hide yes)
			(effects
				(font
					(size 1.27 1.27)
					(thickness 0.15)
				)
			)
		)
		(property "Description" "TVS diode array, 30 kV, USON-10, 3.6 V, 0.55 pF"
			(at 0 0 90)
			(layer "F.Fab")
			(hide yes)
			(effects
				(font
					(size 1.27 1.27)
					(thickness 0.15)
				)
			)
		)
		(property "MPN" "ESD204DQAR"
			(at 0 0 270)
			(unlocked yes)
			(layer "F.Fab")
			(hide yes)
			(effects
				(font
					(size 1 1)
					(thickness 0.15)
				)
			)
		)
		(property "Manufacturer" "Texas Instruments"
			(at 0 0 270)
			(unlocked yes)
			(layer "F.Fab")
			(hide yes)
			(effects
				(font
					(size 1 1)
					(thickness 0.15)
				)
			)
		)
		(property "Author" "Antmicro"
			(at 0 0 270)
			(unlocked yes)
			(layer "F.Fab")
			(hide yes)
			(effects
				(font
					(size 1 1)
					(thickness 0.15)
				)
			)
		)
		(property "License" "Apache-2.0"
			(at 0 0 270)
			(unlocked yes)
			(layer "F.Fab")
			(hide yes)
			(effects
				(font
					(size 1 1)
					(thickness 0.15)
				)
			)
		)
		(sheetname "/OCuLink/")
		(sheetfile "oculink.kicad_sch")
		(attr smd)
		(fp_line
			(start 0.498 1.398)
			(end -0.5 1.398)
			(stroke
				(width 0.15)
				(type solid)
			)
			(layer "F.SilkS")
		)
		(fp_line
			(start 0.498 -1.401)
			(end -0.5 -1.401)
			(stroke
				(width 0.15)
				(type solid)
			)
			(layer "F.SilkS")
		)
		(fp_circle
			(center -0.68 -1.27)
			(end -0.63 -1.27)
			(stroke
				(width 0.15)
				(type solid)
			)
			(fill yes)
			(layer "F.SilkS")
		)
		(fp_rect
			(start -0.8 -1.5)
			(end 0.8 1.499)
			(stroke
				(width 0.05)
				(type solid)
			)
			(fill no)
			(layer "F.CrtYd")
		)
		(fp_line
			(start -0.5 1.249)
			(end 0.498 1.249)
			(stroke
				(width 0.15)
				(type solid)
			)
			(layer "F.Fab")
		)
		(fp_line
			(start -0.5 -1)
			(end -0.5 1.249)
			(stroke
				(width 0.15)
				(type solid)
			)
			(layer "F.Fab")
		)
		(fp_line
			(start -0.25 -1.25)
			(end -0.5 -1)
			(stroke
				(width 0.15)
				(type solid)
			)
			(layer "F.Fab")
		)
		(fp_line
			(start 0.498 -1.25)
			(end 0.498 1.249)
			(stroke
				(width 0.15)
				(type solid)
			)
			(layer "F.Fab")
		)
		(fp_line
			(start 0.498 -1.25)
			(end -0.25 -1.25)
			(stroke
				(width 0.15)
				(type solid)
			)
			(layer "F.Fab")
		)
		(fp_text user "${REFERENCE}"
			(at 0 -0.000501 90)
			(layer "F.Fab")
			(effects
				(font
					(size 0.7 0.7)
					(thickness 0.15)
				)
				(justify right top)
			)
		)
		(fp_text user "License: Apache-2.0"
			(at -0.802 6.9 90)
			(layer "F.Fab")
			(effects
				(font
					(size 0.7 0.7)
					(thickness 0.15)
				)
				(justify right top)
			)
		)
		(fp_text user "Author: Antmicro"
			(at -0.802 5.7 90)
			(layer "F.Fab")
			(effects
				(font
					(size 0.7 0.7)
					(thickness 0.15)
				)
				(justify right top)
			)
		)
		(pad "1" smd roundrect
			(at -0.387 -1 180)
			(size 0.25 0.55)
			(layers "F.Cu" "F.Mask" "F.Paste")
			(roundrect_rratio 0.25)
			(net 81 "/OCuLink/PCIe_{x4}.RX2+")
			(pintype "passive")
		)
		(pad "2" smd roundrect
			(at -0.387 -0.5 180)
			(size 0.25 0.55)
			(layers "F.Cu" "F.Mask" "F.Paste")
			(roundrect_rratio 0.25)
			(net 79 "/OCuLink/PCIe_{x4}.RX2-")
			(pintype "passive")
		)
		(pad "3" smd roundrect
			(at -0.387 0 180)
			(size 0.4 0.55)
			(layers "F.Cu" "F.Mask" "F.Paste")
			(roundrect_rratio 0.25)
			(net 66 "GND")
			(pintype "power_in")
		)
		(pad "4" smd roundrect
			(at -0.387 0.498 180)
			(size 0.25 0.55)
			(layers "F.Cu" "F.Mask" "F.Paste")
			(roundrect_rratio 0.25)
			(net 68 "/OCuLink/PCIe_{x4}.RX3+")
			(pintype "passive")
		)
		(pad "5" smd roundrect
			(at -0.387 0.998 180)
			(size 0.25 0.55)
			(layers "F.Cu" "F.Mask" "F.Paste")
			(roundrect_rratio 0.25)
			(net 67 "/OCuLink/PCIe_{x4}.RX3-")
			(pintype "passive")
		)
		(pad "6" smd roundrect
			(at 0.385 0.998 180)
			(size 0.25 0.55)
			(layers "F.Cu" "F.Mask" "F.Paste")
			(roundrect_rratio 0.25)
			(net 67 "/OCuLink/PCIe_{x4}.RX3-")
			(pintype "passive")
		)
		(pad "7" smd roundrect
			(at 0.385 0.498 180)
			(size 0.25 0.55)
			(layers "F.Cu" "F.Mask" "F.Paste")
			(roundrect_rratio 0.25)
			(net 68 "/OCuLink/PCIe_{x4}.RX3+")
			(pintype "passive")
		)
		(pad "8" smd roundrect
			(at 0.385 0 180)
			(size 0.4 0.55)
			(layers "F.Cu" "F.Mask" "F.Paste")
			(roundrect_rratio 0.25)
			(net 66 "GND")
			(pintype "passive")
		)
		(pad "9" smd roundrect
			(at 0.385 -0.5 180)
			(size 0.25 0.55)
			(layers "F.Cu" "F.Mask" "F.Paste")
			(roundrect_rratio 0.25)
			(net 79 "/OCuLink/PCIe_{x4}.RX2-")
			(pintype "passive")
		)
		(pad "10" smd roundrect
			(at 0.385 -1 180)
			(size 0.25 0.55)
			(layers "F.Cu" "F.Mask" "F.Paste")
			(roundrect_rratio 0.25)
			(net 81 "/OCuLink/PCIe_{x4}.RX2+")
			(pintype "passive")
		)
	)
	(footprint "antmicro-footprints:R_0402_1005Metric"
		(layer "F.Cu")
		(at 118.55 48.2 90)
		(descr "Resistor SMD 0402")
		(tags "resistor SMD 0402")
		(property "Reference" "R44"
			(at -3.2 0.45 90)
			(layer "F.SilkS")
			(effects
				(font
					(size 0.7 0.7)
					(thickness 0.15)
				)
				(justify left bottom)
			)
		)
		(property "Value" "R_0R_0402"
			(at -1.011843 1.772046 90)
			(layer "F.Fab")
			(effects
				(font
					(size 0.7 0.7)
					(thickness 0.15)
				)
				(justify left bottom)
			)
		)
		(property "Datasheet" "https://industrial.panasonic.com/cdbs/www-data/pdf/RDA0000/AOA0000C301.pdf"
			(at 0 0 90)
			(layer "F.Fab")
			(hide yes)
			(effects
				(font
					(size 1.27 1.27)
					(thickness 0.15)
				)
			)
		)
		(property "Description" "SMD Chip Resistor, Jumper, 0 ohm, 100 mW, 0402 [1005 Metric], Thick Film, General Purpose"
			(at 0 0 90)
			(layer "F.Fab")
			(hide yes)
			(effects
				(font
					(size 1.27 1.27)
					(thickness 0.15)
				)
			)
		)
		(property "MPN" "ERJ2GE0R00X"
			(at 0 0 90)
			(unlocked yes)
			(layer "F.Fab")
			(hide yes)
			(effects
				(font
					(size 1 1)
					(thickness 0.15)
				)
			)
		)
		(property "Manufacturer" "Panasonic"
			(at 0 0 90)
			(unlocked yes)
			(layer "F.Fab")
			(hide yes)
			(effects
				(font
					(size 1 1)
					(thickness 0.15)
				)
			)
		)
		(property "License" "Apache-2.0"
			(at 0 0 90)
			(unlocked yes)
			(layer "F.Fab")
			(hide yes)
			(effects
				(font
					(size 1 1)
					(thickness 0.15)
				)
			)
		)
		(property "Author" "Antmicro"
			(at 0 0 90)
			(unlocked yes)
			(layer "F.Fab")
			(hide yes)
			(effects
				(font
					(size 1 1)
					(thickness 0.15)
				)
			)
		)
		(property "Val" "0R"
			(at 0 0 90)
			(unlocked yes)
			(layer "F.Fab")
			(hide yes)
			(effects
				(font
					(size 1 1)
					(thickness 0.15)
				)
			)
		)
		(property "Tolerance" ""
			(at 0 0 90)
			(unlocked yes)
			(layer "F.Fab")
			(hide yes)
			(effects
				(font
					(size 1 1)
					(thickness 0.15)
				)
			)
		)
		(property "Current" "1A"
			(at 0 0 90)
			(unlocked yes)
			(layer "F.Fab")
			(hide yes)
			(effects
				(font
					(size 1 1)
					(thickness 0.15)
				)
			)
		)
		(sheetname "/PCIe-clock-generator/")
		(sheetfile "pcie-clock-generator.kicad_sch")
		(attr smd exclude_from_bom dnp)
		(fp_poly
			(pts
				(xy -0.925 -0.47) (xy 0.925 -0.47) (xy 0.925 0.47) (xy -0.925 0.47)
			)
			(stroke
				(width 0.05)
				(type default)
			)
			(fill no)
			(layer "F.CrtYd")
		)
		(fp_poly
			(pts
				(xy -0.5 -0.25) (xy 0.5 -0.25) (xy 0.5 0.25) (xy -0.5 0.25)
			)
			(stroke
				(width 0.15)
				(type solid)
			)
			(fill no)
			(layer "F.Fab")
		)
		(fp_text user "License: Apache-2.0"
			(at -0.949999 5.169 90)
			(layer "F.Fab")
			(effects
				(font
					(size 0.7 0.7)
					(thickness 0.15)
				)
				(justify left bottom)
			)
		)
		(fp_text user "${REFERENCE}"
			(at -0.95 3.168 90)
			(layer "F.Fab")
			(effects
				(font
					(size 0.7 0.7)
					(thickness 0.15)
				)
				(justify left bottom)
			)
		)
		(fp_text user "Author: Antmicro"
			(at -0.95 4.169 90)
			(layer "F.Fab")
			(effects
				(font
					(size 0.7 0.7)
					(thickness 0.15)
				)
				(justify left bottom)
			)
		)
		(pad "1" smd roundrect
			(at -0.48 0 90)
			(size 0.59 0.64)
			(layers "F.Cu" "F.Mask" "F.Paste")
			(roundrect_rratio 0.25)
			(net 179 "/PCIe-clock-generator/PCIe_{REF1}_R.CK-")
			(pintype "passive")
		)
		(pad "2" smd roundrect
			(at 0.48 0 90)
			(size 0.59 0.64)
			(layers "F.Cu" "F.Mask" "F.Paste")
			(roundrect_rratio 0.25)
			(net 97 "/OCuLink/PCIe_{REF0}.CK-")
			(pintype "passive")
		)
	)
	(footprint "antmicro-footprints:R_0402_1005Metric"
		(layer "F.Cu")
		(at 143.8 63)
		(descr "Resistor SMD 0402")
		(tags "resistor SMD 0402")
		(property "Reference" "R56"
			(at -1.1 -0.6 0)
			(layer "F.SilkS")
			(effects
				(font
					(size 0.7 0.7)
					(thickness 0.15)
				)
				(justify left bottom)
			)
		)
		(property "Value" "R_22R_0402"
			(at -1.011843 1.772047 0)
			(layer "F.Fab")
			(effects
				(font
					(size 0.7 0.7)
					(thickness 0.15)
				)
				(justify left bottom)
			)
		)
		(property "Datasheet" "https://www.bourns.com/docs/product-datasheets/cr.pdf"
			(at 0 0 0)
			(layer "F.Fab")
			(hide yes)
			(effects
				(font
					(size 1.27 1.27)
					(thickness 0.15)
				)
			)
		)
		(property "Description" "SMD Chip Resistor, 22 ohm, ± 1%, 62.5 mW, 0402 [1005 Metric], Thick Film, General Purpose"
			(at 0 0 0)
			(layer "F.Fab")
			(hide yes)
			(effects
				(font
					(size 1.27 1.27)
					(thickness 0.15)
				)
			)
		)
		(property "MPN" "CR0402-FX-22R0GLF"
			(at 0 0 0)
			(unlocked yes)
			(layer "F.Fab")
			(hide yes)
			(effects
				(font
					(size 1 1)
					(thickness 0.15)
				)
			)
		)
		(property "Manufacturer" "Bourns"
			(at 0 0 0)
			(unlocked yes)
			(layer "F.Fab")
			(hide yes)
			(effects
				(font
					(size 1 1)
					(thickness 0.15)
				)
			)
		)
		(property "License" "Apache-2.0"
			(at 0 0 0)
			(unlocked yes)
			(layer "F.Fab")
			(hide yes)
			(effects
				(font
					(size 1 1)
					(thickness 0.15)
				)
			)
		)
		(property "Author" "Antmicro"
			(at 0 0 0)
			(unlocked yes)
			(layer "F.Fab")
			(hide yes)
			(effects
				(font
					(size 1 1)
					(thickness 0.15)
				)
			)
		)
		(property "Val" "22R"
			(at 0 0 0)
			(unlocked yes)
			(layer "F.Fab")
			(hide yes)
			(effects
				(font
					(size 1 1)
					(thickness 0.15)
				)
			)
		)
		(property "Tolerance" "1%"
			(at 0 0 0)
			(unlocked yes)
			(layer "F.Fab")
			(hide yes)
			(effects
				(font
					(size 1 1)
					(thickness 0.15)
				)
			)
		)
		(sheetname "/PCIe-clock-generator/")
		(sheetfile "pcie-clock-generator.kicad_sch")
		(attr smd exclude_from_bom dnp)
		(fp_rect
			(start -0.925 -0.47)
			(end 0.925 0.47)
			(stroke
				(width 0.05)
				(type default)
			)
			(fill no)
			(layer "F.CrtYd")
		)
		(fp_rect
			(start -0.5 -0.25)
			(end 0.5 0.25)
			(stroke
				(width 0.15)
				(type solid)
			)
			(fill no)
			(layer "F.Fab")
		)
		(fp_text user "License: Apache-2.0"
			(at -0.95 5.169 0)
			(layer "F.Fab")
			(effects
				(font
					(size 0.7 0.7)
					(thickness 0.15)
				)
				(justify left bottom)
			)
		)
		(fp_text user "Author: Antmicro"
			(at -0.95 4.169 0)
			(layer "F.Fab")
			(effects
				(font
					(size 0.7 0.7)
					(thickness 0.15)
				)
				(justify left bottom)
			)
		)
		(fp_text user "${REFERENCE}"
			(at -0.95 3.168 0)
			(layer "F.Fab")
			(effects
				(font
					(size 0.7 0.7)
					(thickness 0.15)
				)
				(justify left bottom)
			)
		)
		(pad "1" smd roundrect
			(at -0.48 0)
			(size 0.59 0.64)
			(layers "F.Cu" "F.Mask" "F.Paste")
			(roundrect_rratio 0.25)
			(net 198 "/PCIe-clock-generator/PCIe_{REF1}_R2.CK-")
			(pintype "passive")
		)
		(pad "2" smd roundrect
			(at 0.48 0)
			(size 0.59 0.64)
			(layers "F.Cu" "F.Mask" "F.Paste")
			(roundrect_rratio 0.25)
			(net 179 "/PCIe-clock-generator/PCIe_{REF1}_R.CK-")
			(pintype "passive")
		)
	)
)
